(kicad_pcb
	(version 20260206)
	(generator "pcbnew")
	(generator_version "10.0")
	(general
		(thickness 1.6)
		(legacy_teardrops no)
	)
	(paper "A4")
	(title_block
		(title "04192023_DAF0TMB3IC0_F0TG_MB_C_brd_V02_OCP.brd")
		(comment 1 "Grand Teton / footprints 4219-4226 of 8354")
	)
	(layers
		(0 "F.Cu" signal "TOP")
		(4 "In1.Cu" signal "GND")
		(6 "In2.Cu" signal "IN1")
		(8 "In3.Cu" signal "GND1")
		(10 "In4.Cu" signal "IN2")
		(12 "In5.Cu" signal "GND2")
		(14 "In6.Cu" signal "IN3")
		(16 "In7.Cu" signal "GND3")
		(18 "In8.Cu" signal "VCC")
		(20 "In9.Cu" signal "VCC1")
		(22 "In10.Cu" signal "GND4")
		(24 "In11.Cu" signal "IN4")
		(26 "In12.Cu" signal "GND5")
		(28 "In13.Cu" signal "IN5")
		(30 "In14.Cu" signal "GND6")
		(32 "In15.Cu" signal "IN6")
		(34 "In16.Cu" signal "GND7")
		(2 "B.Cu" signal "BOTTOM")
		(9 "F.Adhes" user "F.Adhesive")
		(11 "B.Adhes" user "B.Adhesive")
		(13 "F.Paste" user "Package Geometry/Pastemask Top")
		(15 "B.Paste" user "Package Geometry/Pastemask Bottom")
		(5 "F.SilkS" user "Ref Des/Silkscreen Top")
		(7 "B.SilkS" user "Ref Des/Silkscreen Bottom")
		(1 "F.Mask" user "Board Geometry/Soldermask Top")
		(3 "B.Mask" user "Board Geometry/Soldermask Bottom")
		(17 "Dwgs.User" user "User.Drawings")
		(19 "Cmts.User" user "User.Comments")
		(21 "Eco1.User" user "User.Eco1")
		(23 "Eco2.User" user "User.Eco2")
		(25 "Edge.Cuts" user "Board Geometry/Outline")
		(27 "Margin" user)
		(31 "F.CrtYd" user "Package Geometry/Place Bound Top")
		(29 "B.CrtYd" user "Package Geometry/Place Bound Bottom")
		(35 "F.Fab" user "Ref Des/Assembly Top")
		(33 "B.Fab" user "Ref Des/Assembly Bottom")
	)
	(footprint ""
		(layer "F.Cu")
		(at 306.832 -354.457 90)
		(property "Reference" "PR68"
			(at 0 0 90)
			(layer "F.SilkS")
			(hide yes)
			(effects
				(font
					(size 1.27 1.27)
				)
			)
		)
		(property "Value" ""
			(at 0 0 90)
			(layer "F.Fab")
			(effects
				(font
					(size 1.27 1.27)
				)
			)
		)
		(duplicate_pad_numbers_are_jumpers no)
		(fp_line
			(start 0.7874 -0.4064)
			(end 0.7874 0.4064)
			(stroke
				(width 0.1524)
				(type default)
			)
			(layer "F.SilkS")
		)
		(fp_line
			(start -0.7874 -0.4064)
			(end 0.7874 -0.4064)
			(stroke
				(width 0.1524)
				(type default)
			)
			(layer "F.SilkS")
		)
		(fp_line
			(start 0.7874 0.4064)
			(end -0.7874 0.4064)
			(stroke
				(width 0.1524)
				(type default)
			)
			(layer "F.SilkS")
		)
		(fp_line
			(start -0.7874 0.4064)
			(end -0.7874 -0.4064)
			(stroke
				(width 0.1524)
				(type default)
			)
			(layer "F.SilkS")
		)
		(fp_line
			(start -0.12065 -0.305054)
			(end -0.12065 -0.2794)
			(stroke
				(width 0.1)
				(type default)
			)
			(layer "F.Fab")
		)
		(fp_line
			(start -0.67945 -0.305054)
			(end -0.12065 -0.305054)
			(stroke
				(width 0.1)
				(type default)
			)
			(layer "F.Fab")
		)
		(fp_line
			(start 0.67945 -0.3048)
			(end 0.67945 0.3048)
			(stroke
				(width 0.1)
				(type default)
			)
			(layer "F.Fab")
		)
		(fp_line
			(start 0.12065 -0.3048)
			(end 0.67945 -0.3048)
			(stroke
				(width 0.1)
				(type default)
			)
			(layer "F.Fab")
		)
		(fp_line
			(start 0.12065 -0.2794)
			(end 0.12065 -0.3048)
			(stroke
				(width 0.1)
				(type default)
			)
			(layer "F.Fab")
		)
		(fp_line
			(start -0.12065 -0.2794)
			(end 0.12065 -0.2794)
			(stroke
				(width 0.1)
				(type default)
			)
			(layer "F.Fab")
		)
		(fp_line
			(start 0.120396 0.2794)
			(end -0.12065 0.2794)
			(stroke
				(width 0.1)
				(type default)
			)
			(layer "F.Fab")
		)
		(fp_line
			(start -0.12065 0.2794)
			(end -0.12065 0.3048)
			(stroke
				(width 0.1)
				(type default)
			)
			(layer "F.Fab")
		)
		(fp_line
			(start 0.67945 0.3048)
			(end 0.120396 0.3048)
			(stroke
				(width 0.1)
				(type default)
			)
			(layer "F.Fab")
		)
		(fp_line
			(start 0.120396 0.3048)
			(end 0.120396 0.2794)
			(stroke
				(width 0.1)
				(type default)
			)
			(layer "F.Fab")
		)
		(fp_line
			(start -0.12065 0.3048)
			(end -0.67945 0.3048)
			(stroke
				(width 0.1)
				(type default)
			)
			(layer "F.Fab")
		)
		(fp_line
			(start -0.67945 0.3048)
			(end -0.67945 -0.305054)
			(stroke
				(width 0.1)
				(type default)
			)
			(layer "F.Fab")
		)
		(pad "1" smd circle
			(at -0.40005 0 90)
			(size 0 0)
			(layers "F.Cu" "F.Mask" "F.Paste")
			(net "VSENSE_PVDDCR_CPU1_P0_DP")
		)
		(pad "2" smd circle
			(at 0.40005 0 90)
			(size 0 0)
			(layers "F.Cu" "F.Mask" "F.Paste")
			(net "VSENSE_PVDDCR_CPU1_P0_VSEN0")
		)
	)
	(footprint ""
		(layer "F.Cu")
		(at 426.974 -421.64 90)
		(property "Reference" "R1483"
			(at 0 0 90)
			(layer "F.SilkS")
			(hide yes)
			(effects
				(font
					(size 1.27 1.27)
				)
			)
		)
		(property "Value" ""
			(at 0 0 90)
			(layer "F.Fab")
			(effects
				(font
					(size 1.27 1.27)
				)
			)
		)
		(duplicate_pad_numbers_are_jumpers no)
		(fp_line
			(start 0.32512 -0.175006)
			(end 0.32512 0.175006)
			(stroke
				(width 0.1)
				(type default)
			)
			(layer "F.Fab")
		)
		(fp_line
			(start -0.32512 -0.175006)
			(end 0.32512 -0.175006)
			(stroke
				(width 0.1)
				(type default)
			)
			(layer "F.Fab")
		)
		(fp_line
			(start 0.32512 0.175006)
			(end -0.32512 0.175006)
			(stroke
				(width 0.1)
				(type default)
			)
			(layer "F.Fab")
		)
		(fp_line
			(start -0.32512 0.175006)
			(end -0.32512 -0.175006)
			(stroke
				(width 0.1)
				(type default)
			)
			(layer "F.Fab")
		)
		(pad "1" smd rect
			(at -0.2667 0 90)
			(size 0.3048 0.381)
			(layers "F.Cu" "F.Mask" "F.Paste")
			(net "P1V8_CPU0_RT_1D")
		)
		(pad "2" smd rect
			(at 0.2667 0 270)
			(size 0.3048 0.381)
			(layers "F.Cu" "F.Mask" "F.Paste")
			(net "JTAG_TMS_RT_CPU0_P3")
		)
	)
	(footprint ""
		(layer "F.Cu")
		(at 162.052 -105.918 -90)
		(property "Reference" "R9025"
			(at 0 0 270)
			(layer "F.SilkS")
			(hide yes)
			(effects
				(font
					(size 1.27 1.27)
				)
			)
		)
		(property "Value" ""
			(at 0 0 270)
			(layer "F.Fab")
			(effects
				(font
					(size 1.27 1.27)
				)
			)
		)
		(duplicate_pad_numbers_are_jumpers no)
		(fp_line
			(start -0.7874 0.4064)
			(end -0.7874 -0.4064)
			(stroke
				(width 0.1524)
				(type default)
			)
			(layer "F.SilkS")
		)
		(fp_line
			(start 0.7874 0.4064)
			(end -0.7874 0.4064)
			(stroke
				(width 0.1524)
				(type default)
			)
			(layer "F.SilkS")
		)
		(fp_line
			(start -0.7874 -0.4064)
			(end 0.7874 -0.4064)
			(stroke
				(width 0.1524)
				(type default)
			)
			(layer "F.SilkS")
		)
		(fp_line
			(start 0.7874 -0.4064)
			(end 0.7874 0.4064)
			(stroke
				(width 0.1524)
				(type default)
			)
			(layer "F.SilkS")
		)
		(fp_line
			(start -0.67945 0.3048)
			(end -0.67945 -0.305054)
			(stroke
				(width 0.1)
				(type default)
			)
			(layer "F.Fab")
		)
		(fp_line
			(start -0.12065 0.3048)
			(end -0.67945 0.3048)
			(stroke
				(width 0.1)
				(type default)
			)
			(layer "F.Fab")
		)
		(fp_line
			(start 0.120396 0.3048)
			(end 0.120396 0.2794)
			(stroke
				(width 0.1)
				(type default)
			)
			(layer "F.Fab")
		)
		(fp_line
			(start 0.67945 0.3048)
			(end 0.120396 0.3048)
			(stroke
				(width 0.1)
				(type default)
			)
			(layer "F.Fab")
		)
		(fp_line
			(start -0.12065 0.2794)
			(end -0.12065 0.3048)
			(stroke
				(width 0.1)
				(type default)
			)
			(layer "F.Fab")
		)
		(fp_line
			(start 0.120396 0.2794)
			(end -0.12065 0.2794)
			(stroke
				(width 0.1)
				(type default)
			)
			(layer "F.Fab")
		)
		(fp_line
			(start -0.12065 -0.2794)
			(end 0.12065 -0.2794)
			(stroke
				(width 0.1)
				(type default)
			)
			(layer "F.Fab")
		)
		(fp_line
			(start 0.12065 -0.2794)
			(end 0.12065 -0.3048)
			(stroke
				(width 0.1)
				(type default)
			)
			(layer "F.Fab")
		)
		(fp_line
			(start 0.12065 -0.3048)
			(end 0.67945 -0.3048)
			(stroke
				(width 0.1)
				(type default)
			)
			(layer "F.Fab")
		)
		(fp_line
			(start 0.67945 -0.3048)
			(end 0.67945 0.3048)
			(stroke
				(width 0.1)
				(type default)
			)
			(layer "F.Fab")
		)
		(fp_line
			(start -0.67945 -0.305054)
			(end -0.12065 -0.305054)
			(stroke
				(width 0.1)
				(type default)
			)
			(layer "F.Fab")
		)
		(fp_line
			(start -0.12065 -0.305054)
			(end -0.12065 -0.2794)
			(stroke
				(width 0.1)
				(type default)
			)
			(layer "F.Fab")
		)
		(pad "1" smd circle
			(at -0.40005 0 270)
			(size 0 0)
			(layers "F.Cu" "F.Mask" "F.Paste")
			(net "IRQ_HSC_FAULT_N")
		)
		(pad "2" smd circle
			(at 0.40005 0 270)
			(size 0 0)
			(layers "F.Cu" "F.Mask" "F.Paste")
			(net "GND")
		)
	)
	(footprint ""
		(layer "F.Cu")
		(at 148.494242 -107.683046)
		(property "Reference" "R334"
			(at 0 0 0)
			(layer "F.SilkS")
			(hide yes)
			(effects
				(font
					(size 1.27 1.27)
				)
			)
		)
		(property "Value" ""
			(at 0 0 0)
			(layer "F.Fab")
			(effects
				(font
					(size 1.27 1.27)
				)
			)
		)
		(duplicate_pad_numbers_are_jumpers no)
		(fp_line
			(start -0.7874 -0.4064)
			(end 0.7874 -0.4064)
			(stroke
				(width 0.1524)
				(type default)
			)
			(layer "F.SilkS")
		)
		(fp_line
			(start -0.7874 0.4064)
			(end -0.7874 -0.4064)
			(stroke
				(width 0.1524)
				(type default)
			)
			(layer "F.SilkS")
		)
		(fp_line
			(start 0.7874 -0.4064)
			(end 0.7874 0.4064)
			(stroke
				(width 0.1524)
				(type default)
			)
			(layer "F.SilkS")
		)
		(fp_line
			(start 0.7874 0.4064)
			(end -0.7874 0.4064)
			(stroke
				(width 0.1524)
				(type default)
			)
			(layer "F.SilkS")
		)
		(fp_line
			(start -0.67945 -0.305054)
			(end -0.12065 -0.305054)
			(stroke
				(width 0.1)
				(type default)
			)
			(layer "F.Fab")
		)
		(fp_line
			(start -0.67945 0.3048)
			(end -0.67945 -0.305054)
			(stroke
				(width 0.1)
				(type default)
			)
			(layer "F.Fab")
		)
		(fp_line
			(start -0.12065 -0.305054)
			(end -0.12065 -0.2794)
			(stroke
				(width 0.1)
				(type default)
			)
			(layer "F.Fab")
		)
		(fp_line
			(start -0.12065 -0.2794)
			(end 0.12065 -0.2794)
			(stroke
				(width 0.1)
				(type default)
			)
			(layer "F.Fab")
		)
		(fp_line
			(start -0.12065 0.2794)
			(end -0.12065 0.3048)
			(stroke
				(width 0.1)
				(type default)
			)
			(layer "F.Fab")
		)
		(fp_line
			(start -0.12065 0.3048)
			(end -0.67945 0.3048)
			(stroke
				(width 0.1)
				(type default)
			)
			(layer "F.Fab")
		)
		(fp_line
			(start 0.120396 0.2794)
			(end -0.12065 0.2794)
			(stroke
				(width 0.1)
				(type default)
			)
			(layer "F.Fab")
		)
		(fp_line
			(start 0.120396 0.3048)
			(end 0.120396 0.2794)
			(stroke
				(width 0.1)
				(type default)
			)
			(layer "F.Fab")
		)
		(fp_line
			(start 0.12065 -0.3048)
			(end 0.67945 -0.3048)
			(stroke
				(width 0.1)
				(type default)
			)
			(layer "F.Fab")
		)
		(fp_line
			(start 0.12065 -0.2794)
			(end 0.12065 -0.3048)
			(stroke
				(width 0.1)
				(type default)
			)
			(layer "F.Fab")
		)
		(fp_line
			(start 0.67945 -0.3048)
			(end 0.67945 0.3048)
			(stroke
				(width 0.1)
				(type default)
			)
			(layer "F.Fab")
		)
		(fp_line
			(start 0.67945 0.3048)
			(end 0.120396 0.3048)
			(stroke
				(width 0.1)
				(type default)
			)
			(layer "F.Fab")
		)
		(pad "1" smd circle
			(at -0.40005 0)
			(size 0 0)
			(layers "F.Cu" "F.Mask" "F.Paste")
			(net "VR_P5V_EN")
		)
		(pad "2" smd circle
			(at 0.40005 0)
			(size 0 0)
			(layers "F.Cu" "F.Mask" "F.Paste")
			(net "GND")
		)
	)
	(footprint ""
		(layer "F.Cu")
		(at 160.856422 -20.068794 -90)
		(property "Reference" "C2078"
			(at 0 0 270)
			(layer "F.SilkS")
			(hide yes)
			(effects
				(font
					(size 1.27 1.27)
				)
			)
		)
		(property "Value" ""
			(at 0 0 270)
			(layer "F.Fab")
			(effects
				(font
					(size 1.27 1.27)
				)
			)
		)
		(duplicate_pad_numbers_are_jumpers no)
		(fp_line
			(start -0.299974 0.150114)
			(end -0.299974 -0.150114)
			(stroke
				(width 0.1)
				(type default)
			)
			(layer "F.Fab")
		)
		(fp_line
			(start 0.299974 0.150114)
			(end -0.299974 0.150114)
			(stroke
				(width 0.1)
				(type default)
			)
			(layer "F.Fab")
		)
		(fp_line
			(start -0.299974 -0.150114)
			(end 0.299974 -0.150114)
			(stroke
				(width 0.1)
				(type default)
			)
			(layer "F.Fab")
		)
		(fp_line
			(start 0.299974 -0.150114)
			(end 0.299974 0.150114)
			(stroke
				(width 0.1)
				(type default)
			)
			(layer "F.Fab")
		)
		(pad "1" smd rect
			(at -0.2667 0 270)
			(size 0.3048 0.381)
			(layers "F.Cu" "F.Mask" "F.Paste")
			(net "P2E_CPU0_P5_TX_DN")
		)
		(pad "2" smd rect
			(at 0.2667 0 270)
			(size 0.3048 0.381)
			(layers "F.Cu" "F.Mask" "F.Paste")
			(net "P2E_CPU0_P5_TX_C_DN")
		)
	)
	(footprint ""
		(layer "F.Cu")
		(at 37.41166 -125.38202 -90)
		(property "Reference" "R1480"
			(at -0.17526 -2.686812 90)
			(unlocked yes)
			(layer "F.SilkS")
			(effects
				(font
					(size 0.7874 0.5842)
					(thickness 0.1524)
				)
				(justify left)
			)
		)
		(property "Value" ""
			(at 0 0 270)
			(layer "F.Fab")
			(effects
				(font
					(size 1.27 1.27)
				)
			)
		)
		(duplicate_pad_numbers_are_jumpers no)
		(fp_line
			(start -4.18973 1.700022)
			(end 4.18973 1.700022)
			(stroke
				(width 0.1524)
				(type default)
			)
			(layer "F.SilkS")
		)
		(fp_line
			(start 4.18973 1.700022)
			(end 4.18973 -1.700022)
			(stroke
				(width 0.1524)
				(type default)
			)
			(layer "F.SilkS")
		)
		(fp_line
			(start -4.18973 -1.700022)
			(end -4.18973 1.700022)
			(stroke
				(width 0.1524)
				(type default)
			)
			(layer "F.SilkS")
		)
		(fp_line
			(start 4.18973 -1.700022)
			(end -4.18973 -1.700022)
			(stroke
				(width 0.1524)
				(type default)
			)
			(layer "F.SilkS")
		)
		(fp_line
			(start -3.24993 1.700022)
			(end 3.24993 1.700022)
			(stroke
				(width 0.1)
				(type default)
			)
			(layer "F.Fab")
		)
		(fp_line
			(start 3.24993 1.700022)
			(end 3.24993 -1.700022)
			(stroke
				(width 0.1)
				(type default)
			)
			(layer "F.Fab")
		)
		(fp_line
			(start -3.24993 -1.700022)
			(end -3.24993 1.700022)
			(stroke
				(width 0.1)
				(type default)
			)
			(layer "F.Fab")
		)
		(fp_line
			(start 3.24993 -1.700022)
			(end -3.24993 -1.700022)
			(stroke
				(width 0.1)
				(type default)
			)
			(layer "F.Fab")
		)
		(pad "1" smd rect
			(at -2.975102 0 270)
			(size 2.159 2.921)
			(layers "F.Cu" "F.Mask" "F.Paste")
			(net "P12V_AUX")
		)
		(pad "2" smd rect
			(at 2.975102 0 270)
			(size 2.159 2.921)
			(layers "F.Cu" "F.Mask" "F.Paste")
			(net "P12V_AUX_DSC")
		)
	)
	(footprint ""
		(layer "F.Cu")
		(at 29.045662 -425.275502)
		(property "Reference" "R3283"
			(at 0 0 0)
			(layer "F.SilkS")
			(hide yes)
			(effects
				(font
					(size 1.27 1.27)
				)
			)
		)
		(property "Value" ""
			(at 0 0 0)
			(layer "F.Fab")
			(effects
				(font
					(size 1.27 1.27)
				)
			)
		)
		(duplicate_pad_numbers_are_jumpers no)
		(fp_line
			(start -0.7874 -0.4064)
			(end 0.7874 -0.4064)
			(stroke
				(width 0.1524)
				(type default)
			)
			(layer "F.SilkS")
		)
		(fp_line
			(start -0.7874 0.4064)
			(end -0.7874 -0.4064)
			(stroke
				(width 0.1524)
				(type default)
			)
			(layer "F.SilkS")
		)
		(fp_line
			(start 0.7874 -0.4064)
			(end 0.7874 0.4064)
			(stroke
				(width 0.1524)
				(type default)
			)
			(layer "F.SilkS")
		)
		(fp_line
			(start 0.7874 0.4064)
			(end -0.7874 0.4064)
			(stroke
				(width 0.1524)
				(type default)
			)
			(layer "F.SilkS")
		)
		(fp_line
			(start -0.67945 -0.305054)
			(end -0.12065 -0.305054)
			(stroke
				(width 0.1)
				(type default)
			)
			(layer "F.Fab")
		)
		(fp_line
			(start -0.67945 0.3048)
			(end -0.67945 -0.305054)
			(stroke
				(width 0.1)
				(type default)
			)
			(layer "F.Fab")
		)
		(fp_line
			(start -0.12065 -0.305054)
			(end -0.12065 -0.2794)
			(stroke
				(width 0.1)
				(type default)
			)
			(layer "F.Fab")
		)
		(fp_line
			(start -0.12065 -0.2794)
			(end 0.12065 -0.2794)
			(stroke
				(width 0.1)
				(type default)
			)
			(layer "F.Fab")
		)
		(fp_line
			(start -0.12065 0.2794)
			(end -0.12065 0.3048)
			(stroke
				(width 0.1)
				(type default)
			)
			(layer "F.Fab")
		)
		(fp_line
			(start -0.12065 0.3048)
			(end -0.67945 0.3048)
			(stroke
				(width 0.1)
				(type default)
			)
			(layer "F.Fab")
		)
		(fp_line
			(start 0.120396 0.2794)
			(end -0.12065 0.2794)
			(stroke
				(width 0.1)
				(type default)
			)
			(layer "F.Fab")
		)
		(fp_line
			(start 0.120396 0.3048)
			(end 0.120396 0.2794)
			(stroke
				(width 0.1)
				(type default)
			)
			(layer "F.Fab")
		)
		(fp_line
			(start 0.12065 -0.3048)
			(end 0.67945 -0.3048)
			(stroke
				(width 0.1)
				(type default)
			)
			(layer "F.Fab")
		)
		(fp_line
			(start 0.12065 -0.2794)
			(end 0.12065 -0.3048)
			(stroke
				(width 0.1)
				(type default)
			)
			(layer "F.Fab")
		)
		(fp_line
			(start 0.67945 -0.3048)
			(end 0.67945 0.3048)
			(stroke
				(width 0.1)
				(type default)
			)
			(layer "F.Fab")
		)
		(fp_line
			(start 0.67945 0.3048)
			(end 0.120396 0.3048)
			(stroke
				(width 0.1)
				(type default)
			)
			(layer "F.Fab")
		)
		(pad "1" smd circle
			(at -0.40005 0)
			(size 0 0)
			(layers "F.Cu" "F.Mask" "F.Paste")
			(net "P3V3_AUX")
		)
		(pad "2" smd circle
			(at 0.40005 0)
			(size 0 0)
			(layers "F.Cu" "F.Mask" "F.Paste")
			(net "FM_P2E_EQB0")
		)
	)
	(footprint ""
		(layer "F.Cu")
		(at 70.346824 -19.929094 180)
		(property "Reference" "C1112"
			(at 0 0 180)
			(layer "F.SilkS")
			(hide yes)
			(effects
				(font
					(size 1.27 1.27)
				)
			)
		)
		(property "Value" ""
			(at 0 0 180)
			(layer "F.Fab")
			(effects
				(font
					(size 1.27 1.27)
				)
			)
		)
		(duplicate_pad_numbers_are_jumpers no)
		(fp_line
			(start 0.7874 0.4064)
			(end -0.7874 0.4064)
			(stroke
				(width 0.1524)
				(type default)
			)
			(layer "F.SilkS")
		)
		(fp_line
			(start 0.7874 -0.4064)
			(end 0.7874 0.4064)
			(stroke
				(width 0.1524)
				(type default)
			)
			(layer "F.SilkS")
		)
		(fp_line
			(start -0.7874 0.4064)
			(end -0.7874 -0.4064)
			(stroke
				(width 0.1524)
				(type default)
			)
			(layer "F.SilkS")
		)
		(fp_line
			(start -0.7874 -0.4064)
			(end 0.7874 -0.4064)
			(stroke
				(width 0.1524)
				(type default)
			)
			(layer "F.SilkS")
		)
		(fp_line
			(start 0.67945 0.3048)
			(end 0.120396 0.3048)
			(stroke
				(width 0.1)
				(type default)
			)
			(layer "F.Fab")
		)
		(fp_line
			(start 0.67945 -0.3048)
			(end 0.67945 0.3048)
			(stroke
				(width 0.1)
				(type default)
			)
			(layer "F.Fab")
		)
		(fp_line
			(start 0.12065 -0.2794)
			(end 0.12065 -0.3048)
			(stroke
				(width 0.1)
				(type default)
			)
			(layer "F.Fab")
		)
		(fp_line
			(start 0.12065 -0.3048)
			(end 0.67945 -0.3048)
			(stroke
				(width 0.1)
				(type default)
			)
			(layer "F.Fab")
		)
		(fp_line
			(start 0.120396 0.3048)
			(end 0.120396 0.2794)
			(stroke
				(width 0.1)
				(type default)
			)
			(layer "F.Fab")
		)
		(fp_line
			(start 0.120396 0.2794)
			(end -0.12065 0.2794)
			(stroke
				(width 0.1)
				(type default)
			)
			(layer "F.Fab")
		)
		(fp_line
			(start -0.12065 0.3048)
			(end -0.67945 0.3048)
			(stroke
				(width 0.1)
				(type default)
			)
			(layer "F.Fab")
		)
		(fp_line
			(start -0.12065 0.2794)
			(end -0.12065 0.3048)
			(stroke
				(width 0.1)
				(type default)
			)
			(layer "F.Fab")
		)
		(fp_line
			(start -0.12065 -0.2794)
			(end 0.12065 -0.2794)
			(stroke
				(width 0.1)
				(type default)
			)
			(layer "F.Fab")
		)
		(fp_line
			(start -0.12065 -0.305054)
			(end -0.12065 -0.2794)
			(stroke
				(width 0.1)
				(type default)
			)
			(layer "F.Fab")
		)
		(fp_line
			(start -0.67945 0.3048)
			(end -0.67945 -0.305054)
			(stroke
				(width 0.1)
				(type default)
			)
			(layer "F.Fab")
		)
		(fp_line
			(start -0.67945 -0.305054)
			(end -0.12065 -0.305054)
			(stroke
				(width 0.1)
				(type default)
			)
			(layer "F.Fab")
		)
		(pad "1" smd circle
			(at -0.40005 0 180)
			(size 0 0)
			(layers "F.Cu" "F.Mask" "F.Paste")
			(net "VSENSE_P12V_INA230_7_INP")
		)
		(pad "2" smd circle
			(at 0.40005 0 180)
			(size 0 0)
			(layers "F.Cu" "F.Mask" "F.Paste")
			(net "VSENSE_P12V_INA230_7_INN")
		)
	)
)
